# S9S_MB_2U (Grand Teton) — schematic netlist excerpt (pin names and nets, part order shuffled) for the footprints in the layout excerpt that follows; sources: Cadence DE-HDL packaged netlist, KiCad conversion of 03242023_DA0F0TMBIJ0_F0T_Motherboard_J_brd_V01_OCP.brd

C708  Q_CAP_DIFFBUS  DIFF BUS_0.22UF 6.3V 20% X6S  pkg C0201  page 177 : \1\ = P5E_CPU1_PE4_TX_C_DN<0> ; \2\ = P5E_CPU1_PE4_TX_DN<0>
R2354  Q_RES  100 1% EMPTY  pkg 0402LF  page 292 : A = PVNN_TERM_CPU1 ; B = SVID_DIO0_CPU1_R

U270  LM75BD  IC  pkg SO8_1-27_4-9X3-9  page 170
  SDA  = SMB_LM75_0_3V3AUX_SDA_R1
  SCL  = SMB_LM75_0_3V3AUX_SCL_R1
  OS  = FM_G751_0_ALERT_N
  GND  = GND
  A2  = U270_0_ADD2
  A1  = U270_0_ADD1
  A0  = U270_0_ADD0
  VCC  = P3V3_AUX

(kicad_pcb
	(version 20260206)
	(generator "pcbnew")
	(generator_version "10.0")
	(general
		(thickness 1.6)
		(legacy_teardrops no)
	)
	(paper "A4")
	(title_block
		(title "03242023_DA0F0TMBIJ0_F0T_Motherboard_J_brd_V01_OCP.brd")
		(comment 1 "Grand Teton / footprints 4129-4131 of 6105")
	)
	(layers
		(0 "F.Cu" signal "TOP")
		(4 "In1.Cu" signal "GND")
		(6 "In2.Cu" signal "IN1")
		(8 "In3.Cu" signal "GND1")
		(10 "In4.Cu" signal "IN2")
		(12 "In5.Cu" signal "GND2")
		(14 "In6.Cu" signal "IN3")
		(16 "In7.Cu" signal "GND3")
		(18 "In8.Cu" signal "VCC")
		(20 "In9.Cu" signal "VCC1")
		(22 "In10.Cu" signal "GND4")
		(24 "In11.Cu" signal "IN4")
		(26 "In12.Cu" signal "GND5")
		(28 "In13.Cu" signal "IN5")
		(30 "In14.Cu" signal "GND6")
		(32 "In15.Cu" signal "IN6")
		(34 "In16.Cu" signal "GND7")
		(2 "B.Cu" signal "BOTTOM")
		(9 "F.Adhes" user "F.Adhesive")
		(11 "B.Adhes" user "B.Adhesive")
		(13 "F.Paste" user "Package Geometry/Pastemask Top")
		(15 "B.Paste" user "Package Geometry/Pastemask Bottom")
		(5 "F.SilkS" user "Ref Des/Silkscreen Top")
		(7 "B.SilkS" user "Ref Des/Silkscreen Bottom")
		(1 "F.Mask" user "Board Geometry/Soldermask Top")
		(3 "B.Mask" user "Board Geometry/Soldermask Bottom")
		(17 "Dwgs.User" user "User.Drawings")
		(19 "Cmts.User" user "User.Comments")
		(21 "Eco1.User" user "User.Eco1")
		(23 "Eco2.User" user "User.Eco2")
		(25 "Edge.Cuts" user "Board Geometry/Outline")
		(27 "Margin" user)
		(31 "F.CrtYd" user "Package Geometry/Place Bound Top")
		(29 "B.CrtYd" user "Package Geometry/Place Bound Bottom")
		(35 "F.Fab" user "Ref Des/Assembly Top")
		(33 "B.Fab" user "Ref Des/Assembly Bottom")
	)
	(footprint ""
		(layer "F.Cu")
		(at 39.194232 -131.897374 180)
		(property "Reference" "R2354"
			(at 0 0 180)
			(layer "F.SilkS")
			(hide yes)
			(effects
				(font
					(size 1.27 1.27)
				)
			)
		)
		(property "Value" ""
			(at 0 0 180)
			(layer "F.Fab")
			(effects
				(font
					(size 1.27 1.27)
				)
			)
		)
		(duplicate_pad_numbers_are_jumpers no)
		(fp_line
			(start 0.7874 0.4064)
			(end -0.7874 0.4064)
			(stroke
				(width 0.1524)
				(type default)
			)
			(layer "F.SilkS")
		)
		(fp_line
			(start 0.7874 -0.4064)
			(end 0.7874 0.4064)
			(stroke
				(width 0.1524)
				(type default)
			)
			(layer "F.SilkS")
		)
		(fp_line
			(start -0.7874 0.4064)
			(end -0.7874 -0.4064)
			(stroke
				(width 0.1524)
				(type default)
			)
			(layer "F.SilkS")
		)
		(fp_line
			(start -0.7874 -0.4064)
			(end 0.7874 -0.4064)
			(stroke
				(width 0.1524)
				(type default)
			)
			(layer "F.SilkS")
		)
		(fp_line
			(start 0.67945 0.3048)
			(end 0.120396 0.3048)
			(stroke
				(width 0.1)
				(type default)
			)
			(layer "F.Fab")
		)
		(fp_line
			(start 0.67945 -0.3048)
			(end 0.67945 0.3048)
			(stroke
				(width 0.1)
				(type default)
			)
			(layer "F.Fab")
		)
		(fp_line
			(start 0.12065 -0.2794)
			(end 0.12065 -0.3048)
			(stroke
				(width 0.1)
				(type default)
			)
			(layer "F.Fab")
		)
		(fp_line
			(start 0.12065 -0.3048)
			(end 0.67945 -0.3048)
			(stroke
				(width 0.1)
				(type default)
			)
			(layer "F.Fab")
		)
		(fp_line
			(start 0.120396 0.3048)
			(end 0.120396 0.2794)
			(stroke
				(width 0.1)
				(type default)
			)
			(layer "F.Fab")
		)
		(fp_line
			(start 0.120396 0.2794)
			(end -0.12065 0.2794)
			(stroke
				(width 0.1)
				(type default)
			)
			(layer "F.Fab")
		)
		(fp_line
			(start -0.12065 0.3048)
			(end -0.67945 0.3048)
			(stroke
				(width 0.1)
				(type default)
			)
			(layer "F.Fab")
		)
		(fp_line
			(start -0.12065 0.2794)
			(end -0.12065 0.3048)
			(stroke
				(width 0.1)
				(type default)
			)
			(layer "F.Fab")
		)
		(fp_line
			(start -0.12065 -0.2794)
			(end 0.12065 -0.2794)
			(stroke
				(width 0.1)
				(type default)
			)
			(layer "F.Fab")
		)
		(fp_line
			(start -0.12065 -0.305054)
			(end -0.12065 -0.2794)
			(stroke
				(width 0.1)
				(type default)
			)
			(layer "F.Fab")
		)
		(fp_line
			(start -0.67945 0.3048)
			(end -0.67945 -0.305054)
			(stroke
				(width 0.1)
				(type default)
			)
			(layer "F.Fab")
		)
		(fp_line
			(start -0.67945 -0.305054)
			(end -0.12065 -0.305054)
			(stroke
				(width 0.1)
				(type default)
			)
			(layer "F.Fab")
		)
		(pad "1" smd circle
			(at -0.40005 0 180)
			(size 0 0)
			(layers "F.Cu" "F.Mask" "F.Paste")
			(net "PVNN_TERM_CPU1")
		)
		(pad "2" smd circle
			(at 0.40005 0 180)
			(size 0 0)
			(layers "F.Cu" "F.Mask" "F.Paste")
			(net "SVID_DIO0_CPU1_R")
		)
	)
	(footprint ""
		(layer "F.Cu")
		(at 49.300638 -408.517344 -90)
		(property "Reference" "C708"
			(at 0 0 270)
			(layer "F.SilkS")
			(hide yes)
			(effects
				(font
					(size 1.27 1.27)
				)
			)
		)
		(property "Value" ""
			(at 0 0 270)
			(layer "F.Fab")
			(effects
				(font
					(size 1.27 1.27)
				)
			)
		)
		(duplicate_pad_numbers_are_jumpers no)
		(fp_line
			(start -0.299974 0.150114)
			(end -0.299974 -0.150114)
			(stroke
				(width 0.1)
				(type default)
			)
			(layer "F.Fab")
		)
		(fp_line
			(start 0.299974 0.150114)
			(end -0.299974 0.150114)
			(stroke
				(width 0.1)
				(type default)
			)
			(layer "F.Fab")
		)
		(fp_line
			(start -0.299974 -0.150114)
			(end 0.299974 -0.150114)
			(stroke
				(width 0.1)
				(type default)
			)
			(layer "F.Fab")
		)
		(fp_line
			(start 0.299974 -0.150114)
			(end 0.299974 0.150114)
			(stroke
				(width 0.1)
				(type default)
			)
			(layer "F.Fab")
		)
		(pad "1" smd rect
			(at -0.2667 0 270)
			(size 0.3048 0.381)
			(layers "F.Cu" "F.Mask" "F.Paste")
			(net "P5E_CPU1_PE4_TX_C_DN<0>")
		)
		(pad "2" smd rect
			(at 0.2667 0 270)
			(size 0.3048 0.381)
			(layers "F.Cu" "F.Mask" "F.Paste")
			(net "P5E_CPU1_PE4_TX_DN<0>")
		)
	)
	(footprint ""
		(layer "F.Cu")
		(at 370.905278 -423.232326 -90)
		(property "Reference" "U270"
			(at -0.413512 -2.776982 0)
			(unlocked yes)
			(layer "F.SilkS")
			(effects
				(font
					(size 0.7874 0.5842)
					(thickness 0.1524)
				)
				(justify left)
			)
		)
		(property "Value" ""
			(at 0 0 270)
			(layer "F.Fab")
			(effects
				(font
					(size 1.27 1.27)
				)
			)
		)
		(duplicate_pad_numbers_are_jumpers no)
		(fp_line
			(start -3.447796 2.500122)
			(end 3.447796 2.500122)
			(stroke
				(width 0.1524)
				(type default)
			)
			(layer "F.SilkS")
		)
		(fp_line
			(start 3.447796 2.500122)
			(end 3.447796 -2.500122)
			(stroke
				(width 0.1524)
				(type default)
			)
			(layer "F.SilkS")
		)
		(fp_line
			(start 0 -1.016)
			(end -1.484122 -2.500122)
			(stroke
				(width 0.1524)
				(type default)
			)
			(layer "F.SilkS")
		)
		(fp_line
			(start -3.447796 -2.500122)
			(end -3.447796 2.500122)
			(stroke
				(width 0.1524)
				(type default)
			)
			(layer "F.SilkS")
		)
		(fp_line
			(start -1.484122 -2.500122)
			(end -3.447796 -2.500122)
			(stroke
				(width 0.1524)
				(type default)
			)
			(layer "F.SilkS")
		)
		(fp_line
			(start 1.484122 -2.500122)
			(end 0 -1.016)
			(stroke
				(width 0.1524)
				(type default)
			)
			(layer "F.SilkS")
		)
		(fp_line
			(start 3.447796 -2.500122)
			(end 1.484122 -2.500122)
			(stroke
				(width 0.1524)
				(type default)
			)
			(layer "F.SilkS")
		)
		(fp_poly
			(pts
				(xy -4.260342 -2.232914) (xy -3.60426 -1.905) (xy -4.260342 -1.577086)
			)
			(stroke
				(width 0)
				(type default)
			)
			(fill yes)
			(layer "F.SilkS")
		)
		(fp_line
			(start -1.999996 2.500122)
			(end 1.999996 2.500122)
			(stroke
				(width 0.1)
				(type default)
			)
			(layer "F.Fab")
		)
		(fp_line
			(start 1.999996 2.500122)
			(end 1.999996 -2.500122)
			(stroke
				(width 0.1)
				(type default)
			)
			(layer "F.Fab")
		)
		(fp_line
			(start -1.999996 -2.500122)
			(end -1.999996 2.500122)
			(stroke
				(width 0.1)
				(type default)
			)
			(layer "F.Fab")
		)
		(fp_line
			(start 1.999996 -2.500122)
			(end -1.999996 -2.500122)
			(stroke
				(width 0.1)
				(type default)
			)
			(layer "F.Fab")
		)
		(fp_poly
			(pts
				(xy -4.5974 -2.413) (xy -4.5974 -1.397) (xy -3.5814 -1.905)
			)
			(stroke
				(width 0)
				(type default)
			)
			(fill yes)
			(layer "F.Fab")
		)
		(pad "1" smd rect
			(at -2.649982 -1.905 180)
			(size 0.6096 1.3208)
			(layers "F.Cu" "F.Mask" "F.Paste")
			(net "SMB_LM75_0_3V3AUX_SDA_R1")
		)
		(pad "2" smd rect
			(at -2.649982 -0.635 180)
			(size 0.6096 1.3208)
			(layers "F.Cu" "F.Mask" "F.Paste")
			(net "SMB_LM75_0_3V3AUX_SCL_R1")
		)
		(pad "3" smd rect
			(at -2.649982 0.635 180)
			(size 0.6096 1.3208)
			(layers "F.Cu" "F.Mask" "F.Paste")
			(net "FM_G751_0_ALERT_N")
		)
		(pad "4" smd rect
			(at -2.649982 1.905 180)
			(size 0.6096 1.3208)
			(layers "F.Cu" "F.Mask" "F.Paste")
			(net "GND")
		)
		(pad "5" smd rect
			(at 2.649982 1.905 180)
			(size 0.6096 1.3208)
			(layers "F.Cu" "F.Mask" "F.Paste")
			(net "U270_0_ADD2")
		)
		(pad "6" smd rect
			(at 2.649982 0.635 180)
			(size 0.6096 1.3208)
			(layers "F.Cu" "F.Mask" "F.Paste")
			(net "U270_0_ADD1")
		)
		(pad "7" smd rect
			(at 2.649982 -0.635 180)
			(size 0.6096 1.3208)
			(layers "F.Cu" "F.Mask" "F.Paste")
			(net "U270_0_ADD0")
		)
		(pad "8" smd rect
			(at 2.649982 -1.905 180)
			(size 0.6096 1.3208)
			(layers "F.Cu" "F.Mask" "F.Paste")
			(net "P3V3_AUX")
		)
	)
)
